# T6G (Grand Teton) — schematic netlist excerpt (pin names and nets, part order shuffled) for the footprints in the layout excerpt that follows; sources: Cadence DE-HDL packaged netlist, KiCad conversion of 04192023_DAF0TMB3IC0_F0TG_MB_C_brd_V02_OCP.brd

R321  Q_RES  0 5% CHIP  pkg 0402LF  page 150 : A = SCM_IRQ_N ; B = IRQ0_A56
R6135  Q_RES  1K 1% CHIP  pkg 0402LF  page 84 : A = FAB_REV_ID0 ; B = GND

(kicad_pcb
	(version 20260206)
	(generator "pcbnew")
	(generator_version "10.0")
	(general
		(thickness 1.6)
		(legacy_teardrops no)
	)
	(paper "A4")
	(title_block
		(title "04192023_DAF0TMB3IC0_F0TG_MB_C_brd_V02_OCP.brd")
		(comment 1 "Grand Teton / footprints 7220-7221 of 8354")
	)
	(layers
		(0 "F.Cu" signal "TOP")
		(4 "In1.Cu" signal "GND")
		(6 "In2.Cu" signal "IN1")
		(8 "In3.Cu" signal "GND1")
		(10 "In4.Cu" signal "IN2")
		(12 "In5.Cu" signal "GND2")
		(14 "In6.Cu" signal "IN3")
		(16 "In7.Cu" signal "GND3")
		(18 "In8.Cu" signal "VCC")
		(20 "In9.Cu" signal "VCC1")
		(22 "In10.Cu" signal "GND4")
		(24 "In11.Cu" signal "IN4")
		(26 "In12.Cu" signal "GND5")
		(28 "In13.Cu" signal "IN5")
		(30 "In14.Cu" signal "GND6")
		(32 "In15.Cu" signal "IN6")
		(34 "In16.Cu" signal "GND7")
		(2 "B.Cu" signal "BOTTOM")
		(9 "F.Adhes" user "F.Adhesive")
		(11 "B.Adhes" user "B.Adhesive")
		(13 "F.Paste" user "Package Geometry/Pastemask Top")
		(15 "B.Paste" user "Package Geometry/Pastemask Bottom")
		(5 "F.SilkS" user "Ref Des/Silkscreen Top")
		(7 "B.SilkS" user "Ref Des/Silkscreen Bottom")
		(1 "F.Mask" user "Board Geometry/Soldermask Top")
		(3 "B.Mask" user "Board Geometry/Soldermask Bottom")
		(17 "Dwgs.User" user "User.Drawings")
		(19 "Cmts.User" user "User.Comments")
		(21 "Eco1.User" user "User.Eco1")
		(23 "Eco2.User" user "User.Eco2")
		(25 "Edge.Cuts" user "Board Geometry/Outline")
		(27 "Margin" user)
		(31 "F.CrtYd" user "Package Geometry/Place Bound Top")
		(29 "B.CrtYd" user "Package Geometry/Place Bound Bottom")
		(35 "F.Fab" user "Ref Des/Assembly Top")
		(33 "B.Fab" user "Ref Des/Assembly Bottom")
	)
	(footprint ""
		(layer "B.Cu")
		(at 395.123162 -200.763632 90)
		(property "Reference" "R6135"
			(at 0 0 90)
			(layer "B.SilkS")
			(hide yes)
			(effects
				(font
					(size 1.27 1.27)
				)
				(justify mirror)
			)
		)
		(property "Value" ""
			(at 0 0 90)
			(layer "B.Fab")
			(effects
				(font
					(size 1.27 1.27)
				)
				(justify mirror)
			)
		)
		(duplicate_pad_numbers_are_jumpers no)
		(fp_line
			(start 0.7874 -0.4064)
			(end -0.7874 -0.4064)
			(stroke
				(width 0.1524)
				(type default)
			)
			(layer "B.SilkS")
		)
		(fp_line
			(start -0.7874 -0.4064)
			(end -0.7874 0.4064)
			(stroke
				(width 0.1524)
				(type default)
			)
			(layer "B.SilkS")
		)
		(fp_line
			(start 0.7874 0.4064)
			(end 0.7874 -0.4064)
			(stroke
				(width 0.1524)
				(type default)
			)
			(layer "B.SilkS")
		)
		(fp_line
			(start -0.7874 0.4064)
			(end 0.7874 0.4064)
			(stroke
				(width 0.1524)
				(type default)
			)
			(layer "B.SilkS")
		)
		(fp_line
			(start 0.67945 -0.305054)
			(end 0.12065 -0.305054)
			(stroke
				(width 0.1)
				(type default)
			)
			(layer "B.Fab")
		)
		(fp_line
			(start 0.12065 -0.305054)
			(end 0.12065 -0.2794)
			(stroke
				(width 0.1)
				(type default)
			)
			(layer "B.Fab")
		)
		(fp_line
			(start -0.12065 -0.3048)
			(end -0.67945 -0.3048)
			(stroke
				(width 0.1)
				(type default)
			)
			(layer "B.Fab")
		)
		(fp_line
			(start -0.67945 -0.3048)
			(end -0.67945 0.3048)
			(stroke
				(width 0.1)
				(type default)
			)
			(layer "B.Fab")
		)
		(fp_line
			(start 0.12065 -0.2794)
			(end -0.12065 -0.2794)
			(stroke
				(width 0.1)
				(type default)
			)
			(layer "B.Fab")
		)
		(fp_line
			(start -0.12065 -0.2794)
			(end -0.12065 -0.3048)
			(stroke
				(width 0.1)
				(type default)
			)
			(layer "B.Fab")
		)
		(fp_line
			(start 0.12065 0.2794)
			(end 0.12065 0.3048)
			(stroke
				(width 0.1)
				(type default)
			)
			(layer "B.Fab")
		)
		(fp_line
			(start -0.120396 0.2794)
			(end 0.12065 0.2794)
			(stroke
				(width 0.1)
				(type default)
			)
			(layer "B.Fab")
		)
		(fp_line
			(start 0.67945 0.3048)
			(end 0.67945 -0.305054)
			(stroke
				(width 0.1)
				(type default)
			)
			(layer "B.Fab")
		)
		(fp_line
			(start 0.12065 0.3048)
			(end 0.67945 0.3048)
			(stroke
				(width 0.1)
				(type default)
			)
			(layer "B.Fab")
		)
		(fp_line
			(start -0.120396 0.3048)
			(end -0.120396 0.2794)
			(stroke
				(width 0.1)
				(type default)
			)
			(layer "B.Fab")
		)
		(fp_line
			(start -0.67945 0.3048)
			(end -0.120396 0.3048)
			(stroke
				(width 0.1)
				(type default)
			)
			(layer "B.Fab")
		)
		(pad "1" smd circle
			(at 0.40005 0 270)
			(size 0 0)
			(layers "B.Cu" "B.Mask" "B.Paste")
			(net "FAB_REV_ID0")
		)
		(pad "2" smd circle
			(at -0.40005 0 270)
			(size 0 0)
			(layers "B.Cu" "B.Mask" "B.Paste")
			(net "GND")
		)
	)
	(footprint ""
		(layer "B.Cu")
		(at 135.919718 -9.02589 -90)
		(property "Reference" "R321"
			(at 0 0 90)
			(layer "B.SilkS")
			(hide yes)
			(effects
				(font
					(size 1.27 1.27)
				)
				(justify mirror)
			)
		)
		(property "Value" ""
			(at 0 0 90)
			(layer "B.Fab")
			(effects
				(font
					(size 1.27 1.27)
				)
				(justify mirror)
			)
		)
		(duplicate_pad_numbers_are_jumpers no)
		(fp_line
			(start -0.7874 0.4064)
			(end 0.7874 0.4064)
			(stroke
				(width 0.1524)
				(type default)
			)
			(layer "B.SilkS")
		)
		(fp_line
			(start 0.7874 0.4064)
			(end 0.7874 -0.4064)
			(stroke
				(width 0.1524)
				(type default)
			)
			(layer "B.SilkS")
		)
		(fp_line
			(start -0.7874 -0.4064)
			(end -0.7874 0.4064)
			(stroke
				(width 0.1524)
				(type default)
			)
			(layer "B.SilkS")
		)
		(fp_line
			(start 0.7874 -0.4064)
			(end -0.7874 -0.4064)
			(stroke
				(width 0.1524)
				(type default)
			)
			(layer "B.SilkS")
		)
		(fp_line
			(start -0.67945 0.3048)
			(end -0.120396 0.3048)
			(stroke
				(width 0.1)
				(type default)
			)
			(layer "B.Fab")
		)
		(fp_line
			(start -0.120396 0.3048)
			(end -0.120396 0.2794)
			(stroke
				(width 0.1)
				(type default)
			)
			(layer "B.Fab")
		)
		(fp_line
			(start 0.12065 0.3048)
			(end 0.67945 0.3048)
			(stroke
				(width 0.1)
				(type default)
			)
			(layer "B.Fab")
		)
		(fp_line
			(start 0.67945 0.3048)
			(end 0.67945 -0.305054)
			(stroke
				(width 0.1)
				(type default)
			)
			(layer "B.Fab")
		)
		(fp_line
			(start -0.120396 0.2794)
			(end 0.12065 0.2794)
			(stroke
				(width 0.1)
				(type default)
			)
			(layer "B.Fab")
		)
		(fp_line
			(start 0.12065 0.2794)
			(end 0.12065 0.3048)
			(stroke
				(width 0.1)
				(type default)
			)
			(layer "B.Fab")
		)
		(fp_line
			(start -0.12065 -0.2794)
			(end -0.12065 -0.3048)
			(stroke
				(width 0.1)
				(type default)
			)
			(layer "B.Fab")
		)
		(fp_line
			(start 0.12065 -0.2794)
			(end -0.12065 -0.2794)
			(stroke
				(width 0.1)
				(type default)
			)
			(layer "B.Fab")
		)
		(fp_line
			(start -0.67945 -0.3048)
			(end -0.67945 0.3048)
			(stroke
				(width 0.1)
				(type default)
			)
			(layer "B.Fab")
		)
		(fp_line
			(start -0.12065 -0.3048)
			(end -0.67945 -0.3048)
			(stroke
				(width 0.1)
				(type default)
			)
			(layer "B.Fab")
		)
		(fp_line
			(start 0.12065 -0.305054)
			(end 0.12065 -0.2794)
			(stroke
				(width 0.1)
				(type default)
			)
			(layer "B.Fab")
		)
		(fp_line
			(start 0.67945 -0.305054)
			(end 0.12065 -0.305054)
			(stroke
				(width 0.1)
				(type default)
			)
			(layer "B.Fab")
		)
		(pad "1" smd circle
			(at 0.40005 0 90)
			(size 0 0)
			(layers "B.Cu" "B.Mask" "B.Paste")
			(net "SCM_IRQ_N")
		)
		(pad "2" smd circle
			(at -0.40005 0 90)
			(size 0 0)
			(layers "B.Cu" "B.Mask" "B.Paste")
			(net "IRQ0_A56")
		)
	)
)
